FILE_TYPE=LIBRARY_PARTS;
primitive 'TPS3700DDCR';
  pin
    'VDD':
      PIN_NUMBER='(5)';
      PINUSE='POWER';
      NO_LOAD_CHECK='Both';
      NO_IO_CHECK='Both';
      NO_ASSERT_CHECK='TRUE';
      NO_DIR_CHECK='TRUE';
      ALLOW_CONNECT='TRUE';
    'INB-':
      PIN_NUMBER='(4)';
      INPUT_LOAD='(-0.01,0.01)';
    'GND':
      PIN_NUMBER='(2)';
      PINUSE='POWER';
      NO_LOAD_CHECK='Both';
      NO_IO_CHECK='Both';
      NO_ASSERT_CHECK='TRUE';
      NO_DIR_CHECK='TRUE';
      ALLOW_CONNECT='TRUE';
    'OUTA':
      PIN_NUMBER='(1)';
      OUTPUT_LOAD='(1.0,-1.0)';
    'INA+':
      PIN_NUMBER='(3)';
      INPUT_LOAD='(-0.01,0.01)';
    'OUTB':
      PIN_NUMBER='(6)';
      OUTPUT_LOAD='(1.0,-1.0)';
  end_pin;
  body
    PART_NAME='TPS3700DDCR';
    BODY_NAME='TPS3700DDCR';
    PHYS_DES_PREFIX='U';
    CLASS='IC';
  end_body;
end_primitive;

END.
